FILE_TYPE = MULTI_PHYS_TABLE;
PART 'SCONN120_H61426002'
{==================================================================================================================================================================================================================}
:PACK_TYPE | MATERIAL | PART_NUMBER     = EnvComp | PART_NUMBER  | JEDEC_TYPE           | CLASS | DESCRIPTION                        | HEIGHT     | COMPONENT_TYPE | LPID   | SPEED_URL | Status |RPL| AML | Bus_Unit | Days;
{==================================================================================================================================================================================================================}
'SM'       | 'CONN'   | 'H61426-002'(!) = ''      | 'H61426-002' | 'SCONN120_H61426002' | 'IO'  | 'CONN,BTB,120P,RCP,VT,0MM,1.27MM'  | '0.258 IN' | 'SMTCONN'      | '3749' | 'http://speed.intel.com:8081/speed/module/pdm/item/pdm_item_detail_direct.asp?item_cde=H61426-002&item_rev=01&url_param=unused' | '' | '' | '' | '' | '' 
'SM'       | 'EMPTY'  | 'H61426-002'(!) = ''      | 'H61426-002' | 'SCONN120_H61426002' | 'IO'  | 'CONN,BTB,120P,RCP,VT,0MM,1.27MM'  | '0.258 IN' | 'SMTCONN'      | '3749' | 'http://speed.intel.com:8081/speed/module/pdm/item/pdm_item_detail_direct.asp?item_cde=H61426-002&item_rev=01&url_param=unused' | '' | '' | '' | '' | '' 
END_PART
END.
